(kicad_pcb
	(version 20260206)
	(generator "pcbnew")
	(generator_version "10.0")
	(general
		(thickness 1.6)
		(legacy_teardrops no)
	)
	(paper "A4")
	(title_block
		(title "01162023_DA0F0TEBIF0_F0T_Expander_BD_F_brd_V02_OCP.brd")
		(comment 1 "Grand Teton / footprint 4451 of 9728 (PEX3), pads 2238-2358 of 2397")
	)
	(layers
		(0 "F.Cu" signal "TOP")
		(4 "In1.Cu" signal "GND")
		(6 "In2.Cu" signal "VCC")
		(8 "In3.Cu" signal "VCC1")
		(10 "In4.Cu" signal "GND1")
		(12 "In5.Cu" signal "IN1")
		(14 "In6.Cu" signal "GND2")
		(16 "In7.Cu" signal "IN2")
		(18 "In8.Cu" signal "GND3")
		(20 "In9.Cu" signal "IN3")
		(22 "In10.Cu" signal "GND4")
		(24 "In11.Cu" signal "IN4")
		(26 "In12.Cu" signal "GND5")
		(28 "In13.Cu" signal "IN5")
		(30 "In14.Cu" signal "GND6")
		(32 "In15.Cu" signal "IN6")
		(34 "In16.Cu" signal "GND7")
		(2 "B.Cu" signal "BOTTOM")
		(9 "F.Adhes" user "F.Adhesive")
		(11 "B.Adhes" user "B.Adhesive")
		(13 "F.Paste" user "Package Geometry/Pastemask Top")
		(15 "B.Paste" user "Package Geometry/Pastemask Bottom")
		(5 "F.SilkS" user "Ref Des/Silkscreen Top")
		(7 "B.SilkS" user "Ref Des/Silkscreen Bottom")
		(1 "F.Mask" user "Board Geometry/Soldermask Top")
		(3 "B.Mask" user "Board Geometry/Soldermask Bottom")
		(17 "Dwgs.User" user "User.Drawings")
		(19 "Cmts.User" user "User.Comments")
		(21 "Eco1.User" user "User.Eco1")
		(23 "Eco2.User" user "User.Eco2")
		(25 "Edge.Cuts" user "Board Geometry/Outline")
		(27 "Margin" user)
		(31 "F.CrtYd" user "Package Geometry/Place Bound Top")
		(29 "B.CrtYd" user "Package Geometry/Place Bound Bottom")
		(35 "F.Fab" user "Ref Des/Assembly Top")
		(33 "B.Fab" user "Ref Des/Assembly Bottom")
	)
	(footprint ""
		(layer "F.Cu")
		(at 407.949908 -295.89984)
		(property "Reference" "PEX3"
			(at -3.358642 35.5727 0)
			(unlocked yes)
			(layer "F.SilkS")
			(effects
				(font
					(size 2.032 1.524)
					(thickness 0.1524)
				)
				(justify left)
			)
		)
		(property "Value" ""
			(at 0 0 0)
			(layer "F.Fab")
			(effects
				(font
					(size 1.27 1.27)
				)
			)
		)
		(duplicate_pad_numbers_are_jumpers no)
		(pad "U37" smd circle
			(at 11.400028 -7.599934)
			(size 0.4572 0.4572)
			(layers "F.Cu" "F.Mask" "F.Paste")
			(net "GND")
		)
		(pad "U38" smd circle
			(at 12.349988 -7.599934)
			(size 0.4572 0.4572)
			(layers "F.Cu" "F.Mask" "F.Paste")
			(net "Net_5411")
		)
		(pad "U39" smd circle
			(at 13.299948 -7.599934)
			(size 0.4572 0.4572)
			(layers "F.Cu" "F.Mask" "F.Paste")
			(net "Net_5405")
		)
		(pad "U40" smd circle
			(at 14.249908 -7.599934)
			(size 0.4572 0.4572)
			(layers "F.Cu" "F.Mask" "F.Paste")
			(net "GND")
		)
		(pad "U41" smd circle
			(at 15.200122 -7.599934)
			(size 0.4572 0.4572)
			(layers "F.Cu" "F.Mask" "F.Paste")
			(net "GND")
		)
		(pad "U42" smd circle
			(at 16.150082 -7.599934)
			(size 0.4572 0.4572)
			(layers "F.Cu" "F.Mask" "F.Paste")
			(net "GND")
		)
		(pad "U43" smd circle
			(at 17.100042 -7.599934)
			(size 0.4572 0.4572)
			(layers "F.Cu" "F.Mask" "F.Paste")
			(net "Net_1549")
		)
		(pad "U44" smd circle
			(at 18.050002 -7.599934)
			(size 0.4572 0.4572)
			(layers "F.Cu" "F.Mask" "F.Paste")
			(net "Net_1522")
		)
		(pad "U45" smd circle
			(at 18.999962 -7.599934)
			(size 0.4572 0.4572)
			(layers "F.Cu" "F.Mask" "F.Paste")
			(net "GND")
		)
		(pad "U46" smd circle
			(at 19.949922 -7.599934)
			(size 0.4572 0.4572)
			(layers "F.Cu" "F.Mask" "F.Paste")
			(net "Net_1486")
		)
		(pad "U47" smd circle
			(at 20.899882 -7.599934)
			(size 0.4572 0.4572)
			(layers "F.Cu" "F.Mask" "F.Paste")
			(net "Net_1501")
		)
		(pad "U48" smd circle
			(at 21.850096 -7.599934)
			(size 0.4572 0.4572)
			(layers "F.Cu" "F.Mask" "F.Paste")
			(net "GND")
		)
		(pad "U49" smd circle
			(at 22.800056 -7.599934)
			(size 0.4572 0.4572)
			(layers "F.Cu" "F.Mask" "F.Paste")
			(net "GND")
		)
		(pad "V1" smd circle
			(at -22.800056 -6.649974)
			(size 0.4572 0.4572)
			(layers "F.Cu" "F.Mask" "F.Paste")
			(net "P5E_PEX3_STN7_RX_DN<113>")
		)
		(pad "V2" smd circle
			(at -21.850096 -6.649974)
			(size 0.4572 0.4572)
			(layers "F.Cu" "F.Mask" "F.Paste")
			(net "P5E_PEX3_STN7_RX_DP<113>")
		)
		(pad "V3" smd circle
			(at -20.899882 -6.649974)
			(size 0.4572 0.4572)
			(layers "F.Cu" "F.Mask" "F.Paste")
			(net "GND")
		)
		(pad "V4" smd circle
			(at -19.949922 -6.649974)
			(size 0.4572 0.4572)
			(layers "F.Cu" "F.Mask" "F.Paste")
			(net "GND")
		)
		(pad "V5" smd circle
			(at -18.999962 -6.649974)
			(size 0.4572 0.4572)
			(layers "F.Cu" "F.Mask" "F.Paste")
			(net "GND")
		)
		(pad "V6" smd circle
			(at -18.050002 -6.649974)
			(size 0.4572 0.4572)
			(layers "F.Cu" "F.Mask" "F.Paste")
			(net "GND")
		)
		(pad "V7" smd circle
			(at -17.100042 -6.649974)
			(size 0.4572 0.4572)
			(layers "F.Cu" "F.Mask" "F.Paste")
			(net "GND")
		)
		(pad "V8" smd circle
			(at -16.150082 -6.649974)
			(size 0.4572 0.4572)
			(layers "F.Cu" "F.Mask" "F.Paste")
			(net "P5E_PEX3_STN7_TX_DN<113>")
		)
		(pad "V9" smd circle
			(at -15.200122 -6.649974)
			(size 0.4572 0.4572)
			(layers "F.Cu" "F.Mask" "F.Paste")
			(net "P5E_PEX3_STN7_TX_DP<113>")
		)
		(pad "V10" smd circle
			(at -14.249908 -6.649974)
			(size 0.4572 0.4572)
			(layers "F.Cu" "F.Mask" "F.Paste")
			(net "GND")
		)
		(pad "V11" smd circle
			(at -13.299948 -6.649974)
			(size 0.4572 0.4572)
			(layers "F.Cu" "F.Mask" "F.Paste")
			(net "GND")
		)
		(pad "V12" smd circle
			(at -12.349988 -6.649974)
			(size 0.4572 0.4572)
			(layers "F.Cu" "F.Mask" "F.Paste")
			(net "GND")
		)
		(pad "V13" smd circle
			(at -11.400028 -6.649974)
			(size 0.4572 0.4572)
			(layers "F.Cu" "F.Mask" "F.Paste")
			(net "GND")
		)
		(pad "V14" smd circle
			(at -10.450068 -6.649974)
			(size 0.4572 0.4572)
			(layers "F.Cu" "F.Mask" "F.Paste")
			(net "P1V8_VDDA_PEX3")
		)
		(pad "V15" smd circle
			(at -9.500108 -6.649974)
			(size 0.4572 0.4572)
			(layers "F.Cu" "F.Mask" "F.Paste")
			(net "GND")
		)
		(pad "V16" smd circle
			(at -8.549894 -6.649974)
			(size 0.4572 0.4572)
			(layers "F.Cu" "F.Mask" "F.Paste")
			(net "P1V25_PEX3")
		)
		(pad "V17" smd circle
			(at -7.599934 -6.649974)
			(size 0.4572 0.4572)
			(layers "F.Cu" "F.Mask" "F.Paste")
			(net "P1V25_PEX3")
		)
		(pad "V18" smd circle
			(at -6.649974 -6.649974)
			(size 0.4572 0.4572)
			(layers "F.Cu" "F.Mask" "F.Paste")
			(net "P1V25_PEX3")
		)
		(pad "V19" smd circle
			(at -5.700014 -6.649974)
			(size 0.4572 0.4572)
			(layers "F.Cu" "F.Mask" "F.Paste")
			(net "P1V25_PEX3")
		)
		(pad "V20" smd circle
			(at -4.750054 -6.649974)
			(size 0.4572 0.4572)
			(layers "F.Cu" "F.Mask" "F.Paste")
			(net "P1V25_PEX3")
		)
		(pad "V21" smd circle
			(at -3.800094 -6.649974)
			(size 0.4572 0.4572)
			(layers "F.Cu" "F.Mask" "F.Paste")
			(net "P1V25_PEX3")
		)
		(pad "V22" smd circle
			(at -2.84988 -6.649974)
			(size 0.4572 0.4572)
			(layers "F.Cu" "F.Mask" "F.Paste")
			(net "P1V25_PEX3")
		)
		(pad "V23" smd circle
			(at -1.89992 -6.649974)
			(size 0.4572 0.4572)
			(layers "F.Cu" "F.Mask" "F.Paste")
			(net "P1V25_PEX3")
		)
		(pad "V24" smd circle
			(at -0.94996 -6.649974)
			(size 0.4572 0.4572)
			(layers "F.Cu" "F.Mask" "F.Paste")
			(net "P1V25_PEX3")
		)
		(pad "V25" smd circle
			(at 0 -6.649974)
			(size 0.4572 0.4572)
			(layers "F.Cu" "F.Mask" "F.Paste")
			(net "P1V25_PEX3")
		)
		(pad "V26" smd circle
			(at 0.94996 -6.649974)
			(size 0.4572 0.4572)
			(layers "F.Cu" "F.Mask" "F.Paste")
			(net "P1V25_PEX3")
		)
		(pad "V27" smd circle
			(at 1.89992 -6.649974)
			(size 0.4572 0.4572)
			(layers "F.Cu" "F.Mask" "F.Paste")
			(net "P1V25_PEX3")
		)
		(pad "V28" smd circle
			(at 2.84988 -6.649974)
			(size 0.4572 0.4572)
			(layers "F.Cu" "F.Mask" "F.Paste")
			(net "P1V25_PEX3")
		)
		(pad "V29" smd circle
			(at 3.800094 -6.649974)
			(size 0.4572 0.4572)
			(layers "F.Cu" "F.Mask" "F.Paste")
			(net "P1V25_PEX3")
		)
		(pad "V30" smd circle
			(at 4.750054 -6.649974)
			(size 0.4572 0.4572)
			(layers "F.Cu" "F.Mask" "F.Paste")
			(net "P1V25_PEX3")
		)
		(pad "V31" smd circle
			(at 5.700014 -6.649974)
			(size 0.4572 0.4572)
			(layers "F.Cu" "F.Mask" "F.Paste")
			(net "P1V25_PEX3")
		)
		(pad "V32" smd circle
			(at 6.649974 -6.649974)
			(size 0.4572 0.4572)
			(layers "F.Cu" "F.Mask" "F.Paste")
			(net "P1V25_PEX3")
		)
		(pad "V33" smd circle
			(at 7.599934 -6.649974)
			(size 0.4572 0.4572)
			(layers "F.Cu" "F.Mask" "F.Paste")
			(net "P1V25_PEX3")
		)
		(pad "V34" smd circle
			(at 8.549894 -6.649974)
			(size 0.4572 0.4572)
			(layers "F.Cu" "F.Mask" "F.Paste")
			(net "GND")
		)
		(pad "V35" smd circle
			(at 9.500108 -6.649974)
			(size 0.4572 0.4572)
			(layers "F.Cu" "F.Mask" "F.Paste")
			(net "P1V8_PEX")
		)
		(pad "V36" smd circle
			(at 10.450068 -6.649974)
			(size 0.4572 0.4572)
			(layers "F.Cu" "F.Mask" "F.Paste")
			(net "GND")
		)
		(pad "V37" smd circle
			(at 11.400028 -6.649974)
			(size 0.4572 0.4572)
			(layers "F.Cu" "F.Mask" "F.Paste")
			(net "GND")
		)
		(pad "V38" smd circle
			(at 12.349988 -6.649974)
			(size 0.4572 0.4572)
			(layers "F.Cu" "F.Mask" "F.Paste")
			(net "GND")
		)
		(pad "V39" smd circle
			(at 13.299948 -6.649974)
			(size 0.4572 0.4572)
			(layers "F.Cu" "F.Mask" "F.Paste")
			(net "VSENSE_P0V8_PEX3_SKT_VSEN")
		)
		(pad "V40" smd circle
			(at 14.249908 -6.649974)
			(size 0.4572 0.4572)
			(layers "F.Cu" "F.Mask" "F.Paste")
			(net "GND")
		)
		(pad "V41" smd circle
			(at 15.200122 -6.649974)
			(size 0.4572 0.4572)
			(layers "F.Cu" "F.Mask" "F.Paste")
			(net "Net_1533")
		)
		(pad "V42" smd circle
			(at 16.150082 -6.649974)
			(size 0.4572 0.4572)
			(layers "F.Cu" "F.Mask" "F.Paste")
			(net "Net_1571")
		)
		(pad "V43" smd circle
			(at 17.100042 -6.649974)
			(size 0.4572 0.4572)
			(layers "F.Cu" "F.Mask" "F.Paste")
			(net "GND")
		)
		(pad "V44" smd circle
			(at 18.050002 -6.649974)
			(size 0.4572 0.4572)
			(layers "F.Cu" "F.Mask" "F.Paste")
			(net "GND")
		)
		(pad "V45" smd circle
			(at 18.999962 -6.649974)
			(size 0.4572 0.4572)
			(layers "F.Cu" "F.Mask" "F.Paste")
			(net "GND")
		)
		(pad "V46" smd circle
			(at 19.949922 -6.649974)
			(size 0.4572 0.4572)
			(layers "F.Cu" "F.Mask" "F.Paste")
			(net "GND")
		)
		(pad "V47" smd circle
			(at 20.899882 -6.649974)
			(size 0.4572 0.4572)
			(layers "F.Cu" "F.Mask" "F.Paste")
			(net "GND")
		)
		(pad "V48" smd circle
			(at 21.850096 -6.649974)
			(size 0.4572 0.4572)
			(layers "F.Cu" "F.Mask" "F.Paste")
			(net "Net_1483")
		)
		(pad "V49" smd circle
			(at 22.800056 -6.649974)
			(size 0.4572 0.4572)
			(layers "F.Cu" "F.Mask" "F.Paste")
			(net "Net_1467")
		)
		(pad "W1" smd circle
			(at -22.800056 -5.700014)
			(size 0.4572 0.4572)
			(layers "F.Cu" "F.Mask" "F.Paste")
			(net "GND")
		)
		(pad "W2" smd circle
			(at -21.850096 -5.700014)
			(size 0.4572 0.4572)
			(layers "F.Cu" "F.Mask" "F.Paste")
			(net "GND")
		)
		(pad "W3" smd circle
			(at -20.899882 -5.700014)
			(size 0.4572 0.4572)
			(layers "F.Cu" "F.Mask" "F.Paste")
			(net "P5E_PEX3_STN7_RX_DN<112>")
		)
		(pad "W4" smd circle
			(at -19.949922 -5.700014)
			(size 0.4572 0.4572)
			(layers "F.Cu" "F.Mask" "F.Paste")
			(net "P5E_PEX3_STN7_RX_DP<112>")
		)
		(pad "W5" smd circle
			(at -18.999962 -5.700014)
			(size 0.4572 0.4572)
			(layers "F.Cu" "F.Mask" "F.Paste")
			(net "GND")
		)
		(pad "W6" smd circle
			(at -18.050002 -5.700014)
			(size 0.4572 0.4572)
			(layers "F.Cu" "F.Mask" "F.Paste")
			(net "P5E_PEX3_STN7_TX_DN<112>")
		)
		(pad "W7" smd circle
			(at -17.100042 -5.700014)
			(size 0.4572 0.4572)
			(layers "F.Cu" "F.Mask" "F.Paste")
			(net "P5E_PEX3_STN7_TX_DP<112>")
		)
		(pad "W8" smd circle
			(at -16.150082 -5.700014)
			(size 0.4572 0.4572)
			(layers "F.Cu" "F.Mask" "F.Paste")
			(net "GND")
		)
		(pad "W9" smd circle
			(at -15.200122 -5.700014)
			(size 0.4572 0.4572)
			(layers "F.Cu" "F.Mask" "F.Paste")
			(net "GND")
		)
		(pad "W10" smd circle
			(at -14.249908 -5.700014)
			(size 0.4572 0.4572)
			(layers "F.Cu" "F.Mask" "F.Paste")
			(net "GND")
		)
		(pad "W11" smd circle
			(at -13.299948 -5.700014)
			(size 0.4572 0.4572)
			(layers "F.Cu" "F.Mask" "F.Paste")
			(net "GND")
		)
		(pad "W12" smd circle
			(at -12.349988 -5.700014)
			(size 0.4572 0.4572)
			(layers "F.Cu" "F.Mask" "F.Paste")
			(net "GND")
		)
		(pad "W13" smd circle
			(at -11.400028 -5.700014)
			(size 0.4572 0.4572)
			(layers "F.Cu" "F.Mask" "F.Paste")
			(net "GND")
		)
		(pad "W14" smd circle
			(at -10.450068 -5.700014)
			(size 0.4572 0.4572)
			(layers "F.Cu" "F.Mask" "F.Paste")
			(net "GND")
		)
		(pad "W15" smd circle
			(at -9.500108 -5.700014)
			(size 0.4572 0.4572)
			(layers "F.Cu" "F.Mask" "F.Paste")
			(net "GND")
		)
		(pad "W16" smd circle
			(at -8.549894 -5.700014)
			(size 0.4572 0.4572)
			(layers "F.Cu" "F.Mask" "F.Paste")
			(net "GND")
		)
		(pad "W17" smd circle
			(at -7.599934 -5.700014)
			(size 0.4572 0.4572)
			(layers "F.Cu" "F.Mask" "F.Paste")
			(net "GND")
		)
		(pad "W18" smd circle
			(at -6.649974 -5.700014)
			(size 0.4572 0.4572)
			(layers "F.Cu" "F.Mask" "F.Paste")
			(net "GND")
		)
		(pad "W19" smd circle
			(at -5.700014 -5.700014)
			(size 0.4572 0.4572)
			(layers "F.Cu" "F.Mask" "F.Paste")
			(net "GND")
		)
		(pad "W20" smd circle
			(at -4.750054 -5.700014)
			(size 0.4572 0.4572)
			(layers "F.Cu" "F.Mask" "F.Paste")
			(net "GND")
		)
		(pad "W21" smd circle
			(at -3.800094 -5.700014)
			(size 0.4572 0.4572)
			(layers "F.Cu" "F.Mask" "F.Paste")
			(net "GND")
		)
		(pad "W22" smd circle
			(at -2.84988 -5.700014)
			(size 0.4572 0.4572)
			(layers "F.Cu" "F.Mask" "F.Paste")
			(net "GND")
		)
		(pad "W23" smd circle
			(at -1.89992 -5.700014)
			(size 0.4572 0.4572)
			(layers "F.Cu" "F.Mask" "F.Paste")
			(net "GND")
		)
		(pad "W24" smd circle
			(at -0.94996 -5.700014)
			(size 0.4572 0.4572)
			(layers "F.Cu" "F.Mask" "F.Paste")
			(net "GND")
		)
		(pad "W25" smd circle
			(at 0 -5.700014)
			(size 0.4572 0.4572)
			(layers "F.Cu" "F.Mask" "F.Paste")
			(net "GND")
		)
		(pad "W26" smd circle
			(at 0.94996 -5.700014)
			(size 0.4572 0.4572)
			(layers "F.Cu" "F.Mask" "F.Paste")
			(net "GND")
		)
		(pad "W27" smd circle
			(at 1.89992 -5.700014)
			(size 0.4572 0.4572)
			(layers "F.Cu" "F.Mask" "F.Paste")
			(net "GND")
		)
		(pad "W28" smd circle
			(at 2.84988 -5.700014)
			(size 0.4572 0.4572)
			(layers "F.Cu" "F.Mask" "F.Paste")
			(net "GND")
		)
		(pad "W29" smd circle
			(at 3.800094 -5.700014)
			(size 0.4572 0.4572)
			(layers "F.Cu" "F.Mask" "F.Paste")
			(net "GND")
		)
		(pad "W30" smd circle
			(at 4.750054 -5.700014)
			(size 0.4572 0.4572)
			(layers "F.Cu" "F.Mask" "F.Paste")
			(net "GND")
		)
		(pad "W31" smd circle
			(at 5.700014 -5.700014)
			(size 0.4572 0.4572)
			(layers "F.Cu" "F.Mask" "F.Paste")
			(net "GND")
		)
		(pad "W32" smd circle
			(at 6.649974 -5.700014)
			(size 0.4572 0.4572)
			(layers "F.Cu" "F.Mask" "F.Paste")
			(net "GND")
		)
		(pad "W33" smd circle
			(at 7.599934 -5.700014)
			(size 0.4572 0.4572)
			(layers "F.Cu" "F.Mask" "F.Paste")
			(net "GND")
		)
		(pad "W34" smd circle
			(at 8.549894 -5.700014)
			(size 0.4572 0.4572)
			(layers "F.Cu" "F.Mask" "F.Paste")
			(net "GND")
		)
		(pad "W35" smd circle
			(at 9.500108 -5.700014)
			(size 0.4572 0.4572)
			(layers "F.Cu" "F.Mask" "F.Paste")
			(net "P1V8_PEX")
		)
		(pad "W36" smd circle
			(at 10.450068 -5.700014)
			(size 0.4572 0.4572)
			(layers "F.Cu" "F.Mask" "F.Paste")
			(net "GND")
		)
		(pad "W37" smd circle
			(at 11.400028 -5.700014)
			(size 0.4572 0.4572)
			(layers "F.Cu" "F.Mask" "F.Paste")
			(net "GND")
		)
		(pad "W38" smd circle
			(at 12.349988 -5.700014)
			(size 0.4572 0.4572)
			(layers "F.Cu" "F.Mask" "F.Paste")
			(net "GND")
		)
		(pad "W39" smd circle
			(at 13.299948 -5.700014)
			(size 0.4572 0.4572)
			(layers "F.Cu" "F.Mask" "F.Paste")
			(net "VSENSE_P0V8_PEX3_SKT_VRTN")
		)
		(pad "W40" smd circle
			(at 14.249908 -5.700014)
			(size 0.4572 0.4572)
			(layers "F.Cu" "F.Mask" "F.Paste")
			(net "GND")
		)
		(pad "W41" smd circle
			(at 15.200122 -5.700014)
			(size 0.4572 0.4572)
			(layers "F.Cu" "F.Mask" "F.Paste")
			(net "GND")
		)
		(pad "W42" smd circle
			(at 16.150082 -5.700014)
			(size 0.4572 0.4572)
			(layers "F.Cu" "F.Mask" "F.Paste")
			(net "GND")
		)
		(pad "W43" smd circle
			(at 17.100042 -5.700014)
			(size 0.4572 0.4572)
			(layers "F.Cu" "F.Mask" "F.Paste")
			(net "Net_1563")
		)
		(pad "W44" smd circle
			(at 18.050002 -5.700014)
			(size 0.4572 0.4572)
			(layers "F.Cu" "F.Mask" "F.Paste")
			(net "Net_1532")
		)
		(pad "W45" smd circle
			(at 18.999962 -5.700014)
			(size 0.4572 0.4572)
			(layers "F.Cu" "F.Mask" "F.Paste")
			(net "GND")
		)
		(pad "W46" smd circle
			(at 19.949922 -5.700014)
			(size 0.4572 0.4572)
			(layers "F.Cu" "F.Mask" "F.Paste")
			(net "Net_1470")
		)
		(pad "W47" smd circle
			(at 20.899882 -5.700014)
			(size 0.4572 0.4572)
			(layers "F.Cu" "F.Mask" "F.Paste")
			(net "Net_1506")
		)
		(pad "W48" smd circle
			(at 21.850096 -5.700014)
			(size 0.4572 0.4572)
			(layers "F.Cu" "F.Mask" "F.Paste")
			(net "GND")
		)
		(pad "W49" smd circle
			(at 22.800056 -5.700014)
			(size 0.4572 0.4572)
			(layers "F.Cu" "F.Mask" "F.Paste")
			(net "GND")
		)
		(pad "Y1" smd circle
			(at -22.800056 -4.750054)
			(size 0.4572 0.4572)
			(layers "F.Cu" "F.Mask" "F.Paste")
			(net "GND")
		)
		(pad "Y2" smd circle
			(at -21.850096 -4.750054)
			(size 0.4572 0.4572)
			(layers "F.Cu" "F.Mask" "F.Paste")
			(net "GND")
		)
		(pad "Y3" smd circle
			(at -20.899882 -4.750054)
			(size 0.4572 0.4572)
			(layers "F.Cu" "F.Mask" "F.Paste")
			(net "GND")
		)
		(pad "Y4" smd circle
			(at -19.949922 -4.750054)
			(size 0.4572 0.4572)
			(layers "F.Cu" "F.Mask" "F.Paste")
			(net "GND")
		)
		(pad "Y5" smd circle
			(at -18.999962 -4.750054)
			(size 0.4572 0.4572)
			(layers "F.Cu" "F.Mask" "F.Paste")
			(net "GND")
		)
		(pad "Y6" smd circle
			(at -18.050002 -4.750054)
			(size 0.4572 0.4572)
			(layers "F.Cu" "F.Mask" "F.Paste")
			(net "GND")
		)
		(pad "Y7" smd circle
			(at -17.100042 -4.750054)
			(size 0.4572 0.4572)
			(layers "F.Cu" "F.Mask" "F.Paste")
			(net "GND")
		)
		(pad "Y8" smd circle
			(at -16.150082 -4.750054)
			(size 0.4572 0.4572)
			(layers "F.Cu" "F.Mask" "F.Paste")
			(net "GND")
		)
		(pad "Y9" smd circle
			(at -15.200122 -4.750054)
			(size 0.4572 0.4572)
			(layers "F.Cu" "F.Mask" "F.Paste")
			(net "GND")
		)
		(pad "Y10" smd circle
			(at -14.249908 -4.750054)
			(size 0.4572 0.4572)
			(layers "F.Cu" "F.Mask" "F.Paste")
			(net "GND")
		)
	)
)
